#ISCELL
  mstr_symbols cad_note *
  *
#ISCELL
  mstr_symbols intel_corp_bpage *
  *
#CELL
  dev_discrete cap_a *
  page155_i127
#ISCELL
  mstr_symbols gnd *
  page155_i128
#CELL
  mstr_discrete fuse *
  page155_i129
#CELL
  mstr_discrete res *
  page155_i130
#CELL
  mstr_conn conn14_h54902001 *
  page155_i171
#CELL
  mstr_ttl ttl1g07_a *
  page155_i178
#ISCELL
  mstr_symbols gnd *
  page155_i180
#ISCELL
  mstr_standard offpage *
  page155_i182
#ISCELL
  mstr_symbols p3v3_stby *
  page155_i183
#CELL
  dev_discrete cap_a *
  page155_i184
#ISCELL
  mstr_symbols gnd *
  page155_i185
#CELL
  mstr_discrete res *
  page155_i186
#CELL
  mstr_discrete fet_n_dual *
  page155_i187
#CELL
  mstr_discrete fet_n_dual *
  page155_i188
#ISCELL
  mstr_symbols p12v_stby *
  page155_i193
#ISCELL
  mstr_symbols p5v_stby *
  page155_i194
#CELL
  mstr_discrete res *
  page155_i196
#ISCELL
  mstr_symbols p5v_stby *
  page155_i197
#CELL
  mstr_discrete res *
  page155_i198
#ISCELL
  mstr_symbols p3v3_stby *
  page155_i199
#CELL
  mstr_discrete res *
  page155_i201
#CELL
  mstr_discrete diode *
  page155_i202
#ISCELL
  mstr_standard offpage *
  page155_i31
#ISCELL
  mstr_standard offpage *
  page155_i32
#ISCELL
  mstr_standard offpage *
  page155_i33
#ISCELL
  mstr_standard offpage *
  page155_i34
#ISCELL
  mstr_standard offpage *
  page155_i37
#ISCELL
  mstr_standard offpage *
  page155_i38
#ISCELL
  mstr_standard offpage *
  page155_i39
#ISCELL
  mstr_standard offpage *
  page155_i40
#ISCELL
  mstr_symbols gnd *
  page155_i41
#ISCELL
  mstr_standard offpage *
  page155_i42
#ISCELL
  mstr_standard offpage *
  page155_i43
#ISCELL
  mstr_standard offpage *
  page155_i52
#CELL
  mstr_discrete res *
  page155_i53
#ISCELL
  mstr_standard offpage *
  page155_i55
#ISCELL
  mstr_standard offpage *
  page155_i56
#ISCELL
  mstr_standard offpage *
  page155_i57
#ISCELL
  mstr_standard offpage *
  page155_i58
#ISCELL
  mstr_standard offpage *
  page155_i59
#ISCELL
  mstr_standard offpage *
  page155_i60
#ISCELL
  mstr_standard offpage *
  page155_i61
#ISCELL
  mstr_standard offpage *
  page155_i62
#ISCELL
  mstr_standard offpage *
  page155_i63
#ISCELL
  mstr_standard offpage *
  page155_i64
#CELL
  mstr_discrete res *
  page155_i65
#CELL
  mstr_discrete res *
  page155_i66
#CELL
  mstr_discrete res *
  page155_i67
#CELL
  mstr_discrete res *
  page155_i68
#ISCELL
  mstr_standard offpage *
  page155_i69
#ISCELL
  mstr_standard offpage *
  page155_i70
#ISCELL
  mstr_standard offpage *
  page155_i71
#ISCELL
  mstr_standard offpage *
  page155_i72
#CELL
  mstr_discrete res *
  page155_i73
#CELL
  mstr_discrete res *
  page155_i74
#CELL
  mstr_discrete res *
  page155_i75
#CELL
  mstr_discrete res *
  page155_i76
#ISCELL
  mstr_standard offpage *
  page155_i77
#ISCELL
  mstr_standard offpage *
  page155_i78
#ISCELL
  mstr_standard offpage *
  page155_i79
#CELL
  mstr_discrete res *
  page155_i80
#ISCELL
  mstr_symbols p3v3_stby *
  page155_i81
